# BASEBOARD_FAB2 (Tioga Pass) — schematic netlist excerpt (pin names and nets, part order shuffled) for the footprints in the layout excerpt that follows; sources: Cadence DE-HDL packaged netlist, KiCad conversion of Wiwynn_Tioga_Pass_MB.brd

CT12  CAP_A  0.1UF 16V 10% X7R  pkg 0402V  page 227 : A = VR_PVDDQ_KLM_AIREF2 ; B = GND
FB1U3  FERRITE  30 FB  pkg SMLF  page 169 : A = A_P1V05_STBY_PCH_SENSOR ; B = P1V05_PCH_STBY

(kicad_pcb
	(version 20260206)
	(generator "pcbnew")
	(generator_version "10.0")
	(general
		(thickness 1.6)
		(legacy_teardrops no)
	)
	(paper "A4")
	(title_block
		(title "Wiwynn_Tioga_Pass_MB.brd")
		(comment 1 "Tioga Pass / footprints 429-430 of 4770")
	)
	(layers
		(0 "F.Cu" signal "TOP")
		(4 "In1.Cu" signal "L2GND")
		(6 "In2.Cu" signal "L3")
		(8 "In3.Cu" signal "L4GND")
		(10 "In4.Cu" signal "L5")
		(12 "In5.Cu" signal "L6GND")
		(14 "In6.Cu" signal "L7VCC")
		(16 "In7.Cu" signal "L8VCC")
		(18 "In8.Cu" signal "L9GND")
		(20 "In9.Cu" signal "L10")
		(22 "In10.Cu" signal "L11GND")
		(24 "In11.Cu" signal "L12")
		(26 "In12.Cu" signal "L13GND")
		(2 "B.Cu" signal "BOTTOM")
		(9 "F.Adhes" user "F.Adhesive")
		(11 "B.Adhes" user "B.Adhesive")
		(13 "F.Paste" user "Package Geometry/Pastemask Top")
		(15 "B.Paste" user "Package Geometry/Pastemask Bottom")
		(5 "F.SilkS" user "Ref Des/Silkscreen Top")
		(7 "B.SilkS" user "Ref Des/Silkscreen Bottom")
		(1 "F.Mask" user "Board Geometry/Soldermask Top")
		(3 "B.Mask" user "Board Geometry/Soldermask Bottom")
		(17 "Dwgs.User" user "User.Drawings")
		(19 "Cmts.User" user "User.Comments")
		(21 "Eco1.User" user "User.Eco1")
		(23 "Eco2.User" user "User.Eco2")
		(25 "Edge.Cuts" user "Board Geometry/Outline")
		(27 "Margin" user)
		(31 "F.CrtYd" user "Package Geometry/Place Bound Top")
		(29 "B.CrtYd" user "Package Geometry/Place Bound Bottom")
		(35 "F.Fab" user "Ref Des/Assembly Top")
		(33 "B.Fab" user "Ref Des/Assembly Bottom")
	)
	(footprint ""
		(layer "F.Cu")
		(at 409.35402 -20.100036)
		(property "Reference" "FB1U3"
			(at 0 0 0)
			(layer "F.SilkS")
			(hide yes)
			(effects
				(font
					(size 1.27 1.27)
				)
			)
		)
		(property "Value" ""
			(at 0 0 0)
			(layer "F.Fab")
			(effects
				(font
					(size 1.27 1.27)
				)
			)
		)
		(duplicate_pad_numbers_are_jumpers no)
		(fp_poly
			(pts
				(xy -0.47625 -0.2413) (xy 0.47625 -0.2413) (xy 0.47625 1.5113) (xy -0.47625 1.5113)
			)
			(stroke
				(width 0)
				(type default)
			)
			(fill no)
			(layer "F.CrtYd")
		)
		(fp_line
			(start -0.47625 -0.2413)
			(end 0.47625 -0.2413)
			(stroke
				(width 0.1)
				(type default)
			)
			(layer "F.Fab")
		)
		(fp_line
			(start -0.47625 1.5113)
			(end -0.47625 -0.2413)
			(stroke
				(width 0.1)
				(type default)
			)
			(layer "F.Fab")
		)
		(fp_line
			(start 0.47625 -0.2413)
			(end 0.47625 1.5113)
			(stroke
				(width 0.1)
				(type default)
			)
			(layer "F.Fab")
		)
		(fp_line
			(start 0.47625 1.5113)
			(end -0.47625 1.5113)
			(stroke
				(width 0.1)
				(type default)
			)
			(layer "F.Fab")
		)
		(pad "1" smd rect
			(at 0 0)
			(size 0.762 0.889)
			(layers "F.Cu" "F.Mask" "F.Paste")
			(net "A_P1V05_STBY_PCH_SENSOR")
		)
		(pad "2" smd rect
			(at 0 1.27)
			(size 0.762 0.889)
			(layers "F.Cu" "F.Mask" "F.Paste")
			(net "P1V05_PCH_STBY")
		)
		(zone
			(layer "F.Cu")
			(hatch none 0.5)
			(connect_pads
				(clearance 0)
			)
			(min_thickness 0.25)
			(keepout
				(tracks allowed)
				(vias not_allowed)
				(pads allowed)
				(copperpour not_allowed)
				(footprints allowed)
			)
			(placement
				(enabled no)
				(sheetname "")
			)
			(fill
				(thermal_gap 0.5)
				(thermal_bridge_width 0.5)
				(island_removal_mode 0)
			)
			(polygon
				(pts
					(xy 408.96794 -19.650456) (xy 409.73502 -19.650456) (xy 409.73502 -19.274536) (xy 408.96794 -19.274536)
				)
			)
		)
		(zone
			(layer "F.Cu")
			(hatch none 0.5)
			(connect_pads
				(clearance 0)
			)
			(min_thickness 0.25)
			(keepout
				(tracks not_allowed)
				(vias allowed)
				(pads allowed)
				(copperpour not_allowed)
				(footprints allowed)
			)
			(placement
				(enabled no)
				(sheetname "")
			)
			(fill
				(thermal_gap 0.5)
				(thermal_bridge_width 0.5)
				(island_removal_mode 0)
			)
			(polygon
				(pts
					(xy 408.96794 -19.274536) (xy 409.73502 -19.274536) (xy 409.73502 -19.650456) (xy 408.96794 -19.650456)
				)
			)
		)
	)
	(footprint ""
		(layer "F.Cu")
		(at -2.1082 -143.256 90)
		(property "Reference" "CT12"
			(at -4.191 0.89027 90)
			(unlocked yes)
			(layer "F.SilkS")
			(effects
				(font
					(size 0.7874 0.5842)
					(thickness 0.1524)
				)
				(justify left)
			)
		)
		(property "Value" ""
			(at 0 0 90)
			(layer "F.Fab")
			(effects
				(font
					(size 1.27 1.27)
				)
			)
		)
		(duplicate_pad_numbers_are_jumpers no)
		(fp_poly
			(pts
				(xy 0.3048 -0.1016) (xy 0.3048 0.9906) (xy -0.3048 0.9906) (xy -0.3048 -0.1016)
			)
			(stroke
				(width 0)
				(type default)
			)
			(fill no)
			(layer "F.CrtYd")
		)
		(fp_line
			(start 0.3048 -0.1016)
			(end -0.3048 -0.1016)
			(stroke
				(width 0.1)
				(type default)
			)
			(layer "F.Fab")
		)
		(fp_line
			(start -0.3048 -0.1016)
			(end -0.3048 0.9906)
			(stroke
				(width 0.1)
				(type default)
			)
			(layer "F.Fab")
		)
		(fp_line
			(start 0.3048 0.9906)
			(end 0.3048 -0.1016)
			(stroke
				(width 0.1)
				(type default)
			)
			(layer "F.Fab")
		)
		(fp_line
			(start -0.3048 0.9906)
			(end 0.3048 0.9906)
			(stroke
				(width 0.1)
				(type default)
			)
			(layer "F.Fab")
		)
		(pad "1" smd rect
			(at 0 0 90)
			(size 0.508 0.508)
			(layers "F.Cu" "F.Mask" "F.Paste")
			(net "VR_PVDDQ_KLM_AIREF2")
		)
		(pad "2" smd rect
			(at 0 0.889 90)
			(size 0.508 0.508)
			(layers "F.Cu" "F.Mask" "F.Paste")
			(net "GND")
		)
		(zone
			(layer "F.Cu")
			(hatch none 0.5)
			(connect_pads
				(clearance 0)
			)
			(min_thickness 0.25)
			(keepout
				(tracks allowed)
				(vias not_allowed)
				(pads allowed)
				(copperpour not_allowed)
				(footprints allowed)
			)
			(placement
				(enabled no)
				(sheetname "")
			)
			(fill
				(thermal_gap 0.5)
				(thermal_bridge_width 0.5)
				(island_removal_mode 0)
			)
			(polygon
				(pts
					(xy -1.8542 -143.002) (xy -1.8542 -143.51) (xy -1.4732 -143.51) (xy -1.4732 -143.002)
				)
			)
		)
		(zone
			(layer "F.Cu")
			(hatch none 0.5)
			(connect_pads
				(clearance 0)
			)
			(min_thickness 0.25)
			(keepout
				(tracks not_allowed)
				(vias allowed)
				(pads allowed)
				(copperpour not_allowed)
				(footprints allowed)
			)
			(placement
				(enabled no)
				(sheetname "")
			)
			(fill
				(thermal_gap 0.5)
				(thermal_bridge_width 0.5)
				(island_removal_mode 0)
			)
			(polygon
				(pts
					(xy -1.4732 -143.002) (xy -1.4732 -143.51) (xy -1.8542 -143.51) (xy -1.8542 -143.002)
				)
			)
		)
	)
)
